(kicad_pcb
	(version 20260206)
	(generator "pcbnew")
	(generator_version "10.0")
	(general
		(thickness 1.6)
		(legacy_teardrops no)
	)
	(paper "A4")
	(title_block
		(title "04192023_DAF0TMB3IC0_F0TG_MB_C_brd_V02_OCP.brd")
		(comment 1 "Grand Teton / footprints 6056-6059 of 8354")
	)
	(layers
		(0 "F.Cu" signal "TOP")
		(4 "In1.Cu" signal "GND")
		(6 "In2.Cu" signal "IN1")
		(8 "In3.Cu" signal "GND1")
		(10 "In4.Cu" signal "IN2")
		(12 "In5.Cu" signal "GND2")
		(14 "In6.Cu" signal "IN3")
		(16 "In7.Cu" signal "GND3")
		(18 "In8.Cu" signal "VCC")
		(20 "In9.Cu" signal "VCC1")
		(22 "In10.Cu" signal "GND4")
		(24 "In11.Cu" signal "IN4")
		(26 "In12.Cu" signal "GND5")
		(28 "In13.Cu" signal "IN5")
		(30 "In14.Cu" signal "GND6")
		(32 "In15.Cu" signal "IN6")
		(34 "In16.Cu" signal "GND7")
		(2 "B.Cu" signal "BOTTOM")
		(9 "F.Adhes" user "F.Adhesive")
		(11 "B.Adhes" user "B.Adhesive")
		(13 "F.Paste" user "Package Geometry/Pastemask Top")
		(15 "B.Paste" user "Package Geometry/Pastemask Bottom")
		(5 "F.SilkS" user "Ref Des/Silkscreen Top")
		(7 "B.SilkS" user "Ref Des/Silkscreen Bottom")
		(1 "F.Mask" user "Board Geometry/Soldermask Top")
		(3 "B.Mask" user "Board Geometry/Soldermask Bottom")
		(17 "Dwgs.User" user "User.Drawings")
		(19 "Cmts.User" user "User.Comments")
		(21 "Eco1.User" user "User.Eco1")
		(23 "Eco2.User" user "User.Eco2")
		(25 "Edge.Cuts" user "Board Geometry/Outline")
		(27 "Margin" user)
		(31 "F.CrtYd" user "Package Geometry/Place Bound Top")
		(29 "B.CrtYd" user "Package Geometry/Place Bound Bottom")
		(35 "F.Fab" user "Ref Des/Assembly Top")
		(33 "B.Fab" user "Ref Des/Assembly Bottom")
	)
	(footprint ""
		(layer "B.Cu")
		(at 306.135278 -244.08511)
		(property "Reference" "R375"
			(at 0 0 0)
			(layer "B.SilkS")
			(hide yes)
			(effects
				(font
					(size 1.27 1.27)
				)
				(justify mirror)
			)
		)
		(property "Value" ""
			(at 0 0 0)
			(layer "B.Fab")
			(effects
				(font
					(size 1.27 1.27)
				)
				(justify mirror)
			)
		)
		(duplicate_pad_numbers_are_jumpers no)
		(fp_line
			(start -0.7874 -0.4064)
			(end -0.7874 0.4064)
			(stroke
				(width 0.1524)
				(type default)
			)
			(layer "B.SilkS")
		)
		(fp_line
			(start -0.7874 0.4064)
			(end 0.7874 0.4064)
			(stroke
				(width 0.1524)
				(type default)
			)
			(layer "B.SilkS")
		)
		(fp_line
			(start 0.7874 -0.4064)
			(end -0.7874 -0.4064)
			(stroke
				(width 0.1524)
				(type default)
			)
			(layer "B.SilkS")
		)
		(fp_line
			(start 0.7874 0.4064)
			(end 0.7874 -0.4064)
			(stroke
				(width 0.1524)
				(type default)
			)
			(layer "B.SilkS")
		)
		(fp_line
			(start -0.67945 -0.3048)
			(end -0.67945 0.3048)
			(stroke
				(width 0.1)
				(type default)
			)
			(layer "B.Fab")
		)
		(fp_line
			(start -0.67945 0.3048)
			(end -0.120396 0.3048)
			(stroke
				(width 0.1)
				(type default)
			)
			(layer "B.Fab")
		)
		(fp_line
			(start -0.12065 -0.3048)
			(end -0.67945 -0.3048)
			(stroke
				(width 0.1)
				(type default)
			)
			(layer "B.Fab")
		)
		(fp_line
			(start -0.12065 -0.2794)
			(end -0.12065 -0.3048)
			(stroke
				(width 0.1)
				(type default)
			)
			(layer "B.Fab")
		)
		(fp_line
			(start -0.120396 0.2794)
			(end 0.12065 0.2794)
			(stroke
				(width 0.1)
				(type default)
			)
			(layer "B.Fab")
		)
		(fp_line
			(start -0.120396 0.3048)
			(end -0.120396 0.2794)
			(stroke
				(width 0.1)
				(type default)
			)
			(layer "B.Fab")
		)
		(fp_line
			(start 0.12065 -0.305054)
			(end 0.12065 -0.2794)
			(stroke
				(width 0.1)
				(type default)
			)
			(layer "B.Fab")
		)
		(fp_line
			(start 0.12065 -0.2794)
			(end -0.12065 -0.2794)
			(stroke
				(width 0.1)
				(type default)
			)
			(layer "B.Fab")
		)
		(fp_line
			(start 0.12065 0.2794)
			(end 0.12065 0.3048)
			(stroke
				(width 0.1)
				(type default)
			)
			(layer "B.Fab")
		)
		(fp_line
			(start 0.12065 0.3048)
			(end 0.67945 0.3048)
			(stroke
				(width 0.1)
				(type default)
			)
			(layer "B.Fab")
		)
		(fp_line
			(start 0.67945 -0.305054)
			(end 0.12065 -0.305054)
			(stroke
				(width 0.1)
				(type default)
			)
			(layer "B.Fab")
		)
		(fp_line
			(start 0.67945 0.3048)
			(end 0.67945 -0.305054)
			(stroke
				(width 0.1)
				(type default)
			)
			(layer "B.Fab")
		)
		(pad "1" smd circle
			(at 0.40005 0 180)
			(size 0 0)
			(layers "B.Cu" "B.Mask" "B.Paste")
			(net "M_A_CPU0_ALERT_N")
		)
		(pad "2" smd circle
			(at -0.40005 0 180)
			(size 0 0)
			(layers "B.Cu" "B.Mask" "B.Paste")
			(net "M_A_CPU0_ALERT_R_N")
		)
	)
	(footprint ""
		(layer "B.Cu")
		(at 95.670878 -144.75841 -90)
		(property "Reference" "PU25"
			(at -3.958844 -4.823714 0)
			(unlocked yes)
			(layer "B.SilkS")
			(effects
				(font
					(size 0.7874 0.5842)
					(thickness 0.1524)
				)
				(justify mirror)
			)
		)
		(property "Value" ""
			(at 0 0 90)
			(layer "B.Fab")
			(effects
				(font
					(size 1.27 1.27)
				)
				(justify mirror)
			)
		)
		(duplicate_pad_numbers_are_jumpers no)
		(fp_line
			(start -3.024886 3.024886)
			(end -2.428494 3.024886)
			(stroke
				(width 0.1524)
				(type default)
			)
			(layer "B.SilkS")
		)
		(fp_line
			(start 2.428494 3.024886)
			(end 3.024886 3.024886)
			(stroke
				(width 0.1524)
				(type default)
			)
			(layer "B.SilkS")
		)
		(fp_line
			(start 3.024886 3.024886)
			(end 3.024886 2.428494)
			(stroke
				(width 0.1524)
				(type default)
			)
			(layer "B.SilkS")
		)
		(fp_line
			(start -3.024886 2.428494)
			(end -3.024886 3.024886)
			(stroke
				(width 0.1524)
				(type default)
			)
			(layer "B.SilkS")
		)
		(fp_line
			(start 3.024886 -2.428494)
			(end 3.024886 -3.024886)
			(stroke
				(width 0.1524)
				(type default)
			)
			(layer "B.SilkS")
		)
		(fp_line
			(start -3.024886 -3.024886)
			(end -3.024886 -2.428494)
			(stroke
				(width 0.1524)
				(type default)
			)
			(layer "B.SilkS")
		)
		(fp_line
			(start -2.428494 -3.024886)
			(end -3.024886 -3.024886)
			(stroke
				(width 0.1524)
				(type default)
			)
			(layer "B.SilkS")
		)
		(fp_line
			(start 3.024886 -3.024886)
			(end 2.428494 -3.024886)
			(stroke
				(width 0.1524)
				(type default)
			)
			(layer "B.SilkS")
		)
		(fp_poly
			(pts
				(xy 5.493004 -2.284222) (xy 5.202682 -1.310386) (xy 4.374134 -2.088134)
			)
			(stroke
				(width 0)
				(type default)
			)
			(fill yes)
			(layer "B.SilkS")
		)
		(fp_line
			(start -3.024886 3.024886)
			(end 3.024886 3.024886)
			(stroke
				(width 0.1)
				(type default)
			)
			(layer "B.Fab")
		)
		(fp_line
			(start 3.024886 3.024886)
			(end 3.024886 -3.024886)
			(stroke
				(width 0.1)
				(type default)
			)
			(layer "B.Fab")
		)
		(fp_line
			(start -3.024886 -3.024886)
			(end -3.024886 3.024886)
			(stroke
				(width 0.1)
				(type default)
			)
			(layer "B.Fab")
		)
		(fp_line
			(start 3.024886 -3.024886)
			(end -3.024886 -3.024886)
			(stroke
				(width 0.1)
				(type default)
			)
			(layer "B.Fab")
		)
		(fp_poly
			(pts
				(xy 3.332226 -2.199894) (xy 4.348226 -1.691894) (xy 4.348226 -2.707894)
			)
			(stroke
				(width 0)
				(type default)
			)
			(fill yes)
			(layer "B.Fab")
		)
		(pad "1" smd rect
			(at 2.875026 -2.199894 180)
			(size 0.1778 0.6604)
			(layers "B.Cu" "B.Mask" "B.Paste")
			(net "PVDDCR_SOC_P1_PWM1")
		)
		(pad "2" smd rect
			(at 2.875026 -1.800098 180)
			(size 0.1778 0.6604)
			(layers "B.Cu" "B.Mask" "B.Paste")
			(net "PVDDCR_SOC_P1_PWM2")
		)
		(pad "3" smd rect
			(at 2.875026 -1.400048 180)
			(size 0.1778 0.6604)
			(layers "B.Cu" "B.Mask" "B.Paste")
			(net "PVDDCR_SOC_P1_PWM3")
		)
		(pad "4" smd rect
			(at 2.875026 -0.999998 180)
			(size 0.1778 0.6604)
			(layers "B.Cu" "B.Mask" "B.Paste")
			(net "NC_PVDDCR_CPU0_P1_PWM9")
		)
		(pad "5" smd rect
			(at 2.875026 -0.599948 180)
			(size 0.1778 0.6604)
			(layers "B.Cu" "B.Mask" "B.Paste")
			(net "NC_PVDDCR_CPU0_P1_PWM8")
		)
		(pad "6" smd rect
			(at 2.875026 -0.199898 180)
			(size 0.1778 0.6604)
			(layers "B.Cu" "B.Mask" "B.Paste")
			(net "NC_PVDDCR_CPU0_P1_PWM7")
		)
		(pad "7" smd rect
			(at 2.875026 0.199898 180)
			(size 0.1778 0.6604)
			(layers "B.Cu" "B.Mask" "B.Paste")
			(net "PVDDCR_CPU0_P1_PWM6")
		)
		(pad "8" smd rect
			(at 2.875026 0.599948 180)
			(size 0.1778 0.6604)
			(layers "B.Cu" "B.Mask" "B.Paste")
			(net "PVDDCR_CPU0_P1_PWM5")
		)
		(pad "9" smd rect
			(at 2.875026 0.999998 180)
			(size 0.1778 0.6604)
			(layers "B.Cu" "B.Mask" "B.Paste")
			(net "PVDDCR_CPU0_P1_PWM4")
		)
		(pad "10" smd rect
			(at 2.875026 1.400048 180)
			(size 0.1778 0.6604)
			(layers "B.Cu" "B.Mask" "B.Paste")
			(net "PVDDCR_CPU0_P1_PWM3")
		)
		(pad "11" smd rect
			(at 2.875026 1.800098 180)
			(size 0.1778 0.6604)
			(layers "B.Cu" "B.Mask" "B.Paste")
			(net "PVDDCR_CPU0_P1_PWM2")
		)
		(pad "12" smd rect
			(at 2.875026 2.199894 180)
			(size 0.1778 0.6604)
			(layers "B.Cu" "B.Mask" "B.Paste")
			(net "PVDDCR_CPU0_P1_PWM1")
		)
		(pad "13" smd rect
			(at 2.199894 2.875026 90)
			(size 0.1778 0.6604)
			(layers "B.Cu" "B.Mask" "B.Paste")
			(net "PVDDCR_CPU0_P1_PMSDA_R")
		)
		(pad "14" smd rect
			(at 1.800098 2.875026 90)
			(size 0.1778 0.6604)
			(layers "B.Cu" "B.Mask" "B.Paste")
			(net "PVDDCR_CPU0_P1_PMSCL_R")
		)
		(pad "15" smd rect
			(at 1.400048 2.875026 90)
			(size 0.1778 0.6604)
			(layers "B.Cu" "B.Mask" "B.Paste")
			(net "PVDDCR_CPU0_P1_PMALERT_R")
		)
		(pad "16" smd rect
			(at 0.999998 2.875026 90)
			(size 0.1778 0.6604)
			(layers "B.Cu" "B.Mask" "B.Paste")
			(net "PWRGD_PVDDCR_CPU0_P1_R")
		)
		(pad "17" smd rect
			(at 0.599948 2.875026 90)
			(size 0.1778 0.6604)
			(layers "B.Cu" "B.Mask" "B.Paste")
			(net "PVDDCR_CPU0_P1_EN_R")
		)
		(pad "18" smd rect
			(at 0.199898 2.875026 90)
			(size 0.1778 0.6604)
			(layers "B.Cu" "B.Mask" "B.Paste")
			(net "PVDDCR_CPU0_P1_RESET_N_R")
		)
		(pad "19" smd rect
			(at -0.199898 2.875026 90)
			(size 0.1778 0.6604)
			(layers "B.Cu" "B.Mask" "B.Paste")
			(net "PVDD18_S5_P1")
		)
		(pad "20" smd rect
			(at -0.599948 2.875026 90)
			(size 0.1778 0.6604)
			(layers "B.Cu" "B.Mask" "B.Paste")
			(net "PWRGD_PVDDCR_SOC_P1_R")
		)
		(pad "21" smd rect
			(at -0.999998 2.875026 90)
			(size 0.1778 0.6604)
			(layers "B.Cu" "B.Mask" "B.Paste")
			(net "SVID_PVDDCR_CPU0_P1_SVD_R1")
		)
		(pad "22" smd rect
			(at -1.400048 2.875026 90)
			(size 0.1778 0.6604)
			(layers "B.Cu" "B.Mask" "B.Paste")
			(net "SVID_PVDDCR_CPU0_P1_SVC_R1")
		)
		(pad "23" smd rect
			(at -1.800098 2.875026 90)
			(size 0.1778 0.6604)
			(layers "B.Cu" "B.Mask" "B.Paste")
			(net "SVID_PVDDCR_CPU0_P1_SVTO_R")
		)
		(pad "24" smd rect
			(at -2.199894 2.875026 90)
			(size 0.1778 0.6604)
			(layers "B.Cu" "B.Mask" "B.Paste")
			(net "SVID_PVDDCR_CPU0_P1_SVTI_R")
		)
		(pad "25" smd rect
			(at -2.875026 2.199894 180)
			(size 0.1778 0.6604)
			(layers "B.Cu" "B.Mask" "B.Paste")
			(net "VSENSE_PVDDCR_CPU0_P1_VSEN0")
		)
		(pad "26" smd rect
			(at -2.875026 1.800098 180)
			(size 0.1778 0.6604)
			(layers "B.Cu" "B.Mask" "B.Paste")
			(net "VSENSE_VSS_SENSE_A_P1")
		)
		(pad "27" smd rect
			(at -2.875026 1.400048 180)
			(size 0.1778 0.6604)
			(layers "B.Cu" "B.Mask" "B.Paste")
			(net "PVDDCR_CPU0_P1_IMON1")
		)
		(pad "28" smd rect
			(at -2.875026 0.999998 180)
			(size 0.1778 0.6604)
			(layers "B.Cu" "B.Mask" "B.Paste")
			(net "PVDDCR_CPU0_P1_IMON2")
		)
		(pad "29" smd rect
			(at -2.875026 0.599948 180)
			(size 0.1778 0.6604)
			(layers "B.Cu" "B.Mask" "B.Paste")
			(net "PVDDCR_CPU0_P1_IMON3")
		)
		(pad "30" smd rect
			(at -2.875026 0.199898 180)
			(size 0.1778 0.6604)
			(layers "B.Cu" "B.Mask" "B.Paste")
			(net "PVDDCR_CPU0_P1_IMON4")
		)
		(pad "31" smd rect
			(at -2.875026 -0.199898 180)
			(size 0.1778 0.6604)
			(layers "B.Cu" "B.Mask" "B.Paste")
			(net "PVDDCR_CPU0_P1_IMON5")
		)
		(pad "32" smd rect
			(at -2.875026 -0.599948 180)
			(size 0.1778 0.6604)
			(layers "B.Cu" "B.Mask" "B.Paste")
			(net "PVDDCR_CPU0_P1_IMON6")
		)
		(pad "33" smd rect
			(at -2.875026 -0.999998 180)
			(size 0.1778 0.6604)
			(layers "B.Cu" "B.Mask" "B.Paste")
			(net "NC_PVDDCR_CPU0_P1_IMON7")
		)
		(pad "34" smd rect
			(at -2.875026 -1.400048 180)
			(size 0.1778 0.6604)
			(layers "B.Cu" "B.Mask" "B.Paste")
			(net "NC_PVDDCR_CPU0_P1_IMON8")
		)
		(pad "35" smd rect
			(at -2.875026 -1.800098 180)
			(size 0.1778 0.6604)
			(layers "B.Cu" "B.Mask" "B.Paste")
			(net "NC_PVDDCR_CPU0_P1_IMON9")
		)
		(pad "36" smd rect
			(at -2.875026 -2.199894 180)
			(size 0.1778 0.6604)
			(layers "B.Cu" "B.Mask" "B.Paste")
			(net "PVDDCR_SOC_P1_IMON3")
		)
		(pad "37" smd rect
			(at -2.199894 -2.875026 90)
			(size 0.1778 0.6604)
			(layers "B.Cu" "B.Mask" "B.Paste")
			(net "PVDDCR_SOC_P1_IMON2")
		)
		(pad "38" smd rect
			(at -1.800098 -2.875026 90)
			(size 0.1778 0.6604)
			(layers "B.Cu" "B.Mask" "B.Paste")
			(net "PVDDCR_SOC_P1_IMON1")
		)
		(pad "39" smd rect
			(at -1.400048 -2.875026 90)
			(size 0.1778 0.6604)
			(layers "B.Cu" "B.Mask" "B.Paste")
			(net "VSENSE_VSS_SENSE_A_P1")
		)
		(pad "40" smd rect
			(at -0.999998 -2.875026 90)
			(size 0.1778 0.6604)
			(layers "B.Cu" "B.Mask" "B.Paste")
			(net "VSENSE_PVDDCR_SOC_P1_VSEN1")
		)
		(pad "41" smd rect
			(at -0.599948 -2.875026 90)
			(size 0.1778 0.6604)
			(layers "B.Cu" "B.Mask" "B.Paste")
			(net "PVDDCR_CPU0_P1_OCP_N_R")
		)
		(pad "42" smd rect
			(at -0.199898 -2.875026 90)
			(size 0.1778 0.6604)
			(layers "B.Cu" "B.Mask" "B.Paste")
			(net "PVDDCR_SOC_P1_EN//ADDR_CFG")
		)
		(pad "43" smd rect
			(at 0.199898 -2.875026 90)
			(size 0.1778 0.6604)
			(layers "B.Cu" "B.Mask" "B.Paste")
			(net "PVDDCR_SOC_P1_TEMP1")
		)
		(pad "44" smd rect
			(at 0.599948 -2.875026 90)
			(size 0.1778 0.6604)
			(layers "B.Cu" "B.Mask" "B.Paste")
			(net "PVDDCR_CPU0_P1_TEMP0")
		)
		(pad "45" smd rect
			(at 0.999998 -2.875026 90)
			(size 0.1778 0.6604)
			(layers "B.Cu" "B.Mask" "B.Paste")
			(net "PVDDCR_CPU0_P1_VMON")
		)
		(pad "46" smd rect
			(at 1.400048 -2.875026 90)
			(size 0.1778 0.6604)
			(layers "B.Cu" "B.Mask" "B.Paste")
			(net "PVDDCR_CPU0_P1_VINSEN")
		)
		(pad "47" smd rect
			(at 1.800098 -2.875026 90)
			(size 0.1778 0.6604)
			(layers "B.Cu" "B.Mask" "B.Paste")
			(net "PVDDCR_CPU0_P1_VCC")
		)
		(pad "48" smd rect
			(at 2.199894 -2.875026 90)
			(size 0.1778 0.6604)
			(layers "B.Cu" "B.Mask" "B.Paste")
			(net "PVDDCR_CPU0_P1_VCCS")
		)
		(pad "TH" smd rect
			(at 0 0 90)
			(size 4.4196 4.4196)
			(layers "B.Cu" "B.Mask" "B.Paste")
			(net "GND")
		)
		(zone
			(layer "B.Cu")
			(hatch none 0.5)
			(connect_pads
				(clearance 0)
			)
			(min_thickness 0.25)
			(keepout
				(tracks not_allowed)
				(vias allowed)
				(pads allowed)
				(copperpour not_allowed)
				(footprints allowed)
			)
			(placement
				(enabled no)
				(sheetname "")
			)
			(fill
				(thermal_gap 0.5)
				(thermal_bridge_width 0.5)
				(island_removal_mode 0)
			)
			(polygon
				(pts
					(xy 95.696278 -142.264384) (xy 98.164904 -142.264384) (xy 98.164904 -147.252436) (xy 93.176852 -147.252436)
					(xy 93.176852 -142.264384) (xy 95.670878 -142.264384) (xy 95.670878 -142.49781) (xy 93.410278 -142.49781)
					(xy 93.410278 -147.01901) (xy 97.931478 -147.01901) (xy 97.931478 -142.49781) (xy 95.696278 -142.49781)
				)
			)
		)
	)
	(footprint ""
		(layer "B.Cu")
		(at 312.978292 -395.148562 90)
		(property "Reference" "C515"
			(at 0 0 90)
			(layer "B.SilkS")
			(hide yes)
			(effects
				(font
					(size 1.27 1.27)
				)
				(justify mirror)
			)
		)
		(property "Value" ""
			(at 0 0 90)
			(layer "B.Fab")
			(effects
				(font
					(size 1.27 1.27)
				)
				(justify mirror)
			)
		)
		(duplicate_pad_numbers_are_jumpers no)
		(fp_line
			(start 0.299974 -0.150114)
			(end -0.299974 -0.150114)
			(stroke
				(width 0.1)
				(type default)
			)
			(layer "B.Fab")
		)
		(fp_line
			(start -0.299974 -0.150114)
			(end -0.299974 0.150114)
			(stroke
				(width 0.1)
				(type default)
			)
			(layer "B.Fab")
		)
		(fp_line
			(start 0.299974 0.150114)
			(end 0.299974 -0.150114)
			(stroke
				(width 0.1)
				(type default)
			)
			(layer "B.Fab")
		)
		(fp_line
			(start -0.299974 0.150114)
			(end 0.299974 0.150114)
			(stroke
				(width 0.1)
				(type default)
			)
			(layer "B.Fab")
		)
		(pad "1" smd rect
			(at 0.2667 0 270)
			(size 0.3048 0.381)
			(layers "B.Cu" "B.Mask" "B.Paste")
			(net "P1V8_CPU0_RT0_1A")
		)
		(pad "2" smd rect
			(at -0.2667 0 270)
			(size 0.3048 0.381)
			(layers "B.Cu" "B.Mask" "B.Paste")
			(net "GND")
		)
	)
	(footprint ""
		(layer "B.Cu")
		(at 113.81486 -34.351468 90)
		(property "Reference" "C6105"
			(at 0 0 90)
			(layer "B.SilkS")
			(hide yes)
			(effects
				(font
					(size 1.27 1.27)
				)
				(justify mirror)
			)
		)
		(property "Value" ""
			(at 0 0 90)
			(layer "B.Fab")
			(effects
				(font
					(size 1.27 1.27)
				)
				(justify mirror)
			)
		)
		(duplicate_pad_numbers_are_jumpers no)
		(fp_line
			(start 1.524 -0.762)
			(end -1.524 -0.762)
			(stroke
				(width 0.1524)
				(type default)
			)
			(layer "B.SilkS")
		)
		(fp_line
			(start -1.524 -0.762)
			(end -1.524 0.762)
			(stroke
				(width 0.1524)
				(type default)
			)
			(layer "B.SilkS")
		)
		(fp_line
			(start 1.524 0.762)
			(end 1.524 -0.762)
			(stroke
				(width 0.1524)
				(type default)
			)
			(layer "B.SilkS")
		)
		(fp_line
			(start -1.524 0.762)
			(end 1.524 0.762)
			(stroke
				(width 0.1524)
				(type default)
			)
			(layer "B.SilkS")
		)
		(fp_line
			(start 1.1049 -0.724916)
			(end 1.1049 0.724916)
			(stroke
				(width 0.1)
				(type default)
			)
			(layer "B.Fab")
		)
		(fp_line
			(start -1.1049 -0.724916)
			(end 1.1049 -0.724916)
			(stroke
				(width 0.1)
				(type default)
			)
			(layer "B.Fab")
		)
		(fp_line
			(start 1.1049 0.724916)
			(end -1.1049 0.724916)
			(stroke
				(width 0.1)
				(type default)
			)
			(layer "B.Fab")
		)
		(fp_line
			(start -1.1049 0.724916)
			(end -1.1049 -0.724916)
			(stroke
				(width 0.1)
				(type default)
			)
			(layer "B.Fab")
		)
		(pad "1" smd rect
			(at 0.889 0 90)
			(size 1.016 1.27)
			(layers "B.Cu" "B.Mask" "B.Paste")
			(net "P1V2_CPU0_USB2_DVDD12")
		)
		(pad "2" smd rect
			(at -0.889 0 90)
			(size 1.016 1.27)
			(layers "B.Cu" "B.Mask" "B.Paste")
			(net "GND")
		)
	)
)
